# S9S_MB_2U (Grand Teton) — schematic netlist excerpt (pin names and nets, part order shuffled) for the footprints in the layout excerpt that follows; sources: Cadence DE-HDL packaged netlist, KiCad conversion of 03242023_DA0F0TMBIJ0_F0T_Motherboard_J_brd_V01_OCP.brd

C1040  Q_CAP  22UF 4V 20% X6S  pkg C0402  page 74 : A = PVCCIN_CPU0 ; B = GND

PL112  Q_INDUCTOR4P_14  150NH IND  pkg L_TLM117513Q-151QL_11X7-5XA  page 268
  \1\  = SW_PVCCIN_CPU0_SW3
  \2\  = IND_P0_CPL3
  \3\  = IND_P0_CPL4
  \4\  = PVCCIN_CPU0

(kicad_pcb
	(version 20260206)
	(generator "pcbnew")
	(generator_version "10.0")
	(general
		(thickness 1.6)
		(legacy_teardrops no)
	)
	(paper "A4")
	(title_block
		(title "03242023_DA0F0TMBIJ0_F0T_Motherboard_J_brd_V01_OCP.brd")
		(comment 1 "Grand Teton / footprints 2916-2917 of 6105")
	)
	(layers
		(0 "F.Cu" signal "TOP")
		(4 "In1.Cu" signal "GND")
		(6 "In2.Cu" signal "IN1")
		(8 "In3.Cu" signal "GND1")
		(10 "In4.Cu" signal "IN2")
		(12 "In5.Cu" signal "GND2")
		(14 "In6.Cu" signal "IN3")
		(16 "In7.Cu" signal "GND3")
		(18 "In8.Cu" signal "VCC")
		(20 "In9.Cu" signal "VCC1")
		(22 "In10.Cu" signal "GND4")
		(24 "In11.Cu" signal "IN4")
		(26 "In12.Cu" signal "GND5")
		(28 "In13.Cu" signal "IN5")
		(30 "In14.Cu" signal "GND6")
		(32 "In15.Cu" signal "IN6")
		(34 "In16.Cu" signal "GND7")
		(2 "B.Cu" signal "BOTTOM")
		(9 "F.Adhes" user "F.Adhesive")
		(11 "B.Adhes" user "B.Adhesive")
		(13 "F.Paste" user "Package Geometry/Pastemask Top")
		(15 "B.Paste" user "Package Geometry/Pastemask Bottom")
		(5 "F.SilkS" user "Ref Des/Silkscreen Top")
		(7 "B.SilkS" user "Ref Des/Silkscreen Bottom")
		(1 "F.Mask" user "Board Geometry/Soldermask Top")
		(3 "B.Mask" user "Board Geometry/Soldermask Bottom")
		(17 "Dwgs.User" user "User.Drawings")
		(19 "Cmts.User" user "User.Comments")
		(21 "Eco1.User" user "User.Eco1")
		(23 "Eco2.User" user "User.Eco2")
		(25 "Edge.Cuts" user "Board Geometry/Outline")
		(27 "Margin" user)
		(31 "F.CrtYd" user "Package Geometry/Place Bound Top")
		(29 "B.CrtYd" user "Package Geometry/Place Bound Bottom")
		(35 "F.Fab" user "Ref Des/Assembly Top")
		(33 "B.Fab" user "Ref Des/Assembly Bottom")
	)
	(footprint ""
		(layer "F.Cu")
		(at 361.288838 -324.445376)
		(property "Reference" "PL112"
			(at 15.670022 5.810758 0)
			(unlocked yes)
			(layer "F.SilkS")
			(effects
				(font
					(size 0.7874 0.5842)
					(thickness 0.1524)
				)
				(justify left)
			)
		)
		(property "Value" ""
			(at 0 0 0)
			(layer "F.Fab")
			(effects
				(font
					(size 1.27 1.27)
				)
			)
		)
		(duplicate_pad_numbers_are_jumpers no)
		(fp_line
			(start -3.750056 -5.500116)
			(end -2.393442 -5.500116)
			(stroke
				(width 0.1524)
				(type default)
			)
			(layer "F.SilkS")
		)
		(fp_line
			(start -3.750056 5.500116)
			(end -3.750056 -5.500116)
			(stroke
				(width 0.1524)
				(type default)
			)
			(layer "F.SilkS")
		)
		(fp_line
			(start -2.393442 5.500116)
			(end -3.750056 5.500116)
			(stroke
				(width 0.1524)
				(type default)
			)
			(layer "F.SilkS")
		)
		(fp_line
			(start 2.393442 5.500116)
			(end 3.750056 5.500116)
			(stroke
				(width 0.1524)
				(type default)
			)
			(layer "F.SilkS")
		)
		(fp_line
			(start 3.750056 -5.500116)
			(end 2.393442 -5.500116)
			(stroke
				(width 0.1524)
				(type default)
			)
			(layer "F.SilkS")
		)
		(fp_line
			(start 3.750056 -4.449572)
			(end 3.750056 -5.500116)
			(stroke
				(width 0.1524)
				(type default)
			)
			(layer "F.SilkS")
		)
		(fp_line
			(start 3.750056 5.500116)
			(end 3.750056 -3.687572)
			(stroke
				(width 0.1524)
				(type default)
			)
			(layer "F.SilkS")
		)
		(fp_poly
			(pts
				(xy -3.380994 -7.001764) (xy -3.021838 -5.924042) (xy -4.099306 -6.283198)
			)
			(stroke
				(width 0)
				(type default)
			)
			(fill yes)
			(layer "F.SilkS")
		)
		(fp_line
			(start -3.750056 -5.500116)
			(end -3.750056 5.500116)
			(stroke
				(width 0.1)
				(type default)
			)
			(layer "F.Fab")
		)
		(fp_line
			(start -3.750056 5.500116)
			(end 3.750056 5.500116)
			(stroke
				(width 0.1)
				(type default)
			)
			(layer "F.Fab")
		)
		(fp_line
			(start 3.750056 -5.500116)
			(end -3.750056 -5.500116)
			(stroke
				(width 0.1)
				(type default)
			)
			(layer "F.Fab")
		)
		(fp_line
			(start 3.750056 5.500116)
			(end 3.750056 -5.500116)
			(stroke
				(width 0.1)
				(type default)
			)
			(layer "F.Fab")
		)
		(fp_poly
			(pts
				(xy -4.9276 -4.757928) (xy -4.9276 -3.741928) (xy -3.9116 -4.249928)
			)
			(stroke
				(width 0)
				(type default)
			)
			(fill yes)
			(layer "F.Fab")
		)
		(pad "1" smd rect
			(at 0 -4.249928 270)
			(size 2.413 4.5212)
			(layers "F.Cu" "F.Mask" "F.Paste")
			(net "SW_PVCCIN_CPU0_SW3")
		)
		(pad "2" smd rect
			(at 0 -1.175004 270)
			(size 1.3716 4.5212)
			(layers "F.Cu" "F.Mask" "F.Paste")
			(net "IND_P0_CPL3")
		)
		(pad "3" smd rect
			(at 0 1.175004 270)
			(size 1.3716 4.5212)
			(layers "F.Cu" "F.Mask" "F.Paste")
			(net "IND_P0_CPL4")
		)
		(pad "4" smd rect
			(at 0 4.249928 270)
			(size 2.413 4.5212)
			(layers "F.Cu" "F.Mask" "F.Paste")
			(net "PVCCIN_CPU0")
		)
	)
	(footprint ""
		(layer "F.Cu")
		(at 366.48263 -251.375418 90)
		(property "Reference" "C1040"
			(at 0 0 90)
			(layer "F.SilkS")
			(hide yes)
			(effects
				(font
					(size 1.27 1.27)
				)
			)
		)
		(property "Value" ""
			(at 0 0 90)
			(layer "F.Fab")
			(effects
				(font
					(size 1.27 1.27)
				)
			)
		)
		(duplicate_pad_numbers_are_jumpers no)
		(fp_line
			(start 0.7874 -0.4064)
			(end 0.7874 0.4064)
			(stroke
				(width 0.1524)
				(type default)
			)
			(layer "F.SilkS")
		)
		(fp_line
			(start -0.7874 -0.4064)
			(end 0.7874 -0.4064)
			(stroke
				(width 0.1524)
				(type default)
			)
			(layer "F.SilkS")
		)
		(fp_line
			(start 0.7874 0.4064)
			(end -0.7874 0.4064)
			(stroke
				(width 0.1524)
				(type default)
			)
			(layer "F.SilkS")
		)
		(fp_line
			(start -0.7874 0.4064)
			(end -0.7874 -0.4064)
			(stroke
				(width 0.1524)
				(type default)
			)
			(layer "F.SilkS")
		)
		(fp_line
			(start -0.12065 -0.305054)
			(end -0.12065 -0.2794)
			(stroke
				(width 0.1)
				(type default)
			)
			(layer "F.Fab")
		)
		(fp_line
			(start -0.67945 -0.305054)
			(end -0.12065 -0.305054)
			(stroke
				(width 0.1)
				(type default)
			)
			(layer "F.Fab")
		)
		(fp_line
			(start 0.67945 -0.3048)
			(end 0.67945 0.3048)
			(stroke
				(width 0.1)
				(type default)
			)
			(layer "F.Fab")
		)
		(fp_line
			(start 0.12065 -0.3048)
			(end 0.67945 -0.3048)
			(stroke
				(width 0.1)
				(type default)
			)
			(layer "F.Fab")
		)
		(fp_line
			(start 0.12065 -0.2794)
			(end 0.12065 -0.3048)
			(stroke
				(width 0.1)
				(type default)
			)
			(layer "F.Fab")
		)
		(fp_line
			(start -0.12065 -0.2794)
			(end 0.12065 -0.2794)
			(stroke
				(width 0.1)
				(type default)
			)
			(layer "F.Fab")
		)
		(fp_line
			(start 0.120396 0.2794)
			(end -0.12065 0.2794)
			(stroke
				(width 0.1)
				(type default)
			)
			(layer "F.Fab")
		)
		(fp_line
			(start -0.12065 0.2794)
			(end -0.12065 0.3048)
			(stroke
				(width 0.1)
				(type default)
			)
			(layer "F.Fab")
		)
		(fp_line
			(start 0.67945 0.3048)
			(end 0.120396 0.3048)
			(stroke
				(width 0.1)
				(type default)
			)
			(layer "F.Fab")
		)
		(fp_line
			(start 0.120396 0.3048)
			(end 0.120396 0.2794)
			(stroke
				(width 0.1)
				(type default)
			)
			(layer "F.Fab")
		)
		(fp_line
			(start -0.12065 0.3048)
			(end -0.67945 0.3048)
			(stroke
				(width 0.1)
				(type default)
			)
			(layer "F.Fab")
		)
		(fp_line
			(start -0.67945 0.3048)
			(end -0.67945 -0.305054)
			(stroke
				(width 0.1)
				(type default)
			)
			(layer "F.Fab")
		)
		(pad "1" smd circle
			(at -0.40005 0 90)
			(size 0 0)
			(layers "F.Cu" "F.Mask" "F.Paste")
			(net "PVCCIN_CPU0")
		)
		(pad "2" smd circle
			(at 0.40005 0 90)
			(size 0 0)
			(layers "F.Cu" "F.Mask" "F.Paste")
			(net "GND")
		)
	)
)
